(kicad_pcb
	(version 20260206)
	(generator "pcbnew")
	(generator_version "10.0")
	(general
		(thickness 1.6)
		(legacy_teardrops no)
	)
	(paper "A4")
	(title_block
		(title "peb — Lightning_PEB_BRD.brd")
		(comment 1 "Lightning (Wiwynn / Facebook NVMe JBOF) / footprints 261-268 of 2563")
	)
	(layers
		(0 "F.Cu" signal "TOP")
		(4 "In1.Cu" signal "L2GND")
		(6 "In2.Cu" signal "L3")
		(8 "In3.Cu" signal "L4VCC")
		(10 "In4.Cu" signal "L5VCC")
		(12 "In5.Cu" signal "L6")
		(14 "In6.Cu" signal "L7GND")
		(2 "B.Cu" signal "BOTTOM")
		(9 "F.Adhes" user "F.Adhesive")
		(11 "B.Adhes" user "B.Adhesive")
		(13 "F.Paste" user "Package Geometry/Pastemask Top")
		(15 "B.Paste" user "Package Geometry/Pastemask Bottom")
		(5 "F.SilkS" user "Ref Des/Silkscreen Top")
		(7 "B.SilkS" user "Ref Des/Silkscreen Bottom")
		(1 "F.Mask" user "Board Geometry/Soldermask Top")
		(3 "B.Mask" user "Board Geometry/Soldermask Bottom")
		(17 "Dwgs.User" user "User.Drawings")
		(19 "Cmts.User" user "User.Comments")
		(21 "Eco1.User" user "User.Eco1")
		(23 "Eco2.User" user "User.Eco2")
		(25 "Edge.Cuts" user "Board Geometry/Outline")
		(27 "Margin" user)
		(31 "F.CrtYd" user "Package Geometry/Place Bound Top")
		(29 "B.CrtYd" user "Package Geometry/Place Bound Bottom")
		(35 "F.Fab" user "Ref Des/Assembly Top")
		(33 "B.Fab" user "Ref Des/Assembly Bottom")
	)
	(footprint ""
		(layer "F.Cu")
		(at 66.792094 -212.420454 180)
		(property "Reference" "C355"
			(at 0 0 180)
			(layer "F.SilkS")
			(hide yes)
			(effects
				(font
					(size 1.27 1.27)
				)
			)
		)
		(property "Value" "SCD22U10V2KX-1GP"
			(at 1.1811 -2.7051 180)
			(unlocked yes)
			(layer "F.Fab")
			(hide yes)
			(effects
				(font
					(size 1.016 1.016)
					(thickness 0.1524)
				)
			)
		)
		(property "Device Type" "C402H22"
			(at 1.1811 -4.2291 180)
			(unlocked yes)
			(layer "F.Fab")
			(hide yes)
			(effects
				(font
					(size 1.016 1.016)
					(thickness 0.1524)
				)
			)
		)
		(duplicate_pad_numbers_are_jumpers no)
		(fp_rect
			(start -0.4318 0.9525)
			(end 0.4318 -0.9525)
			(stroke
				(width 0)
				(type default)
			)
			(fill no)
			(layer "F.CrtYd")
		)
		(fp_rect
			(start -0.4318 0.9525)
			(end 0.4318 -0.9525)
			(stroke
				(width 0)
				(type default)
			)
			(fill no)
			(layer "F.Fab")
		)
		(pad "1" smd custom
			(at 0 -0.4445 180)
			(size 0.1524 0.1524)
			(layers "F.Cu" "F.Mask" "F.Paste")
			(net "PCIE_TX_CAP_P70")
			(options
				(clearance outline)
				(anchor circle)
			)
			(primitives
				(gr_poly
					(pts
						(arc
							(start 0.3048 -0.2032)
							(mid 0.275042 -0.275042)
							(end 0.2032 -0.3048)
						)
						(arc
							(start -0.2032 -0.3048)
							(mid -0.275042 -0.275042)
							(end -0.3048 -0.2032)
						)
						(arc
							(start -0.3048 0.2032)
							(mid -0.275042 0.275042)
							(end -0.2032 0.3048)
						)
						(arc
							(start 0.2032 0.3048)
							(mid 0.275042 0.275042)
							(end 0.3048 0.2032)
						)
					)
					(width 0)
					(fill yes)
				)
			)
		)
		(pad "2" smd custom
			(at 0 0.4445 180)
			(size 0.1524 0.1524)
			(layers "F.Cu" "F.Mask" "F.Paste")
			(net "PCIE_TX_P70")
			(options
				(clearance outline)
				(anchor circle)
			)
			(primitives
				(gr_poly
					(pts
						(arc
							(start 0.3048 -0.2032)
							(mid 0.275042 -0.275042)
							(end 0.2032 -0.3048)
						)
						(arc
							(start -0.2032 -0.3048)
							(mid -0.275042 -0.275042)
							(end -0.3048 -0.2032)
						)
						(arc
							(start -0.3048 0.2032)
							(mid -0.275042 0.275042)
							(end -0.2032 0.3048)
						)
						(arc
							(start 0.2032 0.3048)
							(mid 0.275042 0.275042)
							(end 0.3048 0.2032)
						)
					)
					(width 0)
					(fill yes)
				)
			)
		)
	)
	(footprint ""
		(layer "F.Cu")
		(at 193.592196 -212.420454 180)
		(property "Reference" "C121"
			(at 0 0 180)
			(layer "F.SilkS")
			(hide yes)
			(effects
				(font
					(size 1.27 1.27)
				)
			)
		)
		(property "Value" "SCD22U10V2KX-1GP"
			(at 1.1811 -2.7051 180)
			(unlocked yes)
			(layer "F.Fab")
			(hide yes)
			(effects
				(font
					(size 1.016 1.016)
					(thickness 0.1524)
				)
			)
		)
		(property "Device Type" "C402H22"
			(at 1.1811 -4.2291 180)
			(unlocked yes)
			(layer "F.Fab")
			(hide yes)
			(effects
				(font
					(size 1.016 1.016)
					(thickness 0.1524)
				)
			)
		)
		(duplicate_pad_numbers_are_jumpers no)
		(fp_rect
			(start -0.4318 0.9525)
			(end 0.4318 -0.9525)
			(stroke
				(width 0)
				(type default)
			)
			(fill no)
			(layer "F.CrtYd")
		)
		(fp_rect
			(start -0.4318 0.9525)
			(end 0.4318 -0.9525)
			(stroke
				(width 0)
				(type default)
			)
			(fill no)
			(layer "F.Fab")
		)
		(pad "1" smd custom
			(at 0 -0.4445 180)
			(size 0.1524 0.1524)
			(layers "F.Cu" "F.Mask" "F.Paste")
			(net "PCIE_TX_CAP_P44")
			(options
				(clearance outline)
				(anchor circle)
			)
			(primitives
				(gr_poly
					(pts
						(arc
							(start 0.3048 -0.2032)
							(mid 0.275042 -0.275042)
							(end 0.2032 -0.3048)
						)
						(arc
							(start -0.2032 -0.3048)
							(mid -0.275042 -0.275042)
							(end -0.3048 -0.2032)
						)
						(arc
							(start -0.3048 0.2032)
							(mid -0.275042 0.275042)
							(end -0.2032 0.3048)
						)
						(arc
							(start 0.2032 0.3048)
							(mid 0.275042 0.275042)
							(end 0.3048 0.2032)
						)
					)
					(width 0)
					(fill yes)
				)
			)
		)
		(pad "2" smd custom
			(at 0 0.4445 180)
			(size 0.1524 0.1524)
			(layers "F.Cu" "F.Mask" "F.Paste")
			(net "PCIE_TX_P44")
			(options
				(clearance outline)
				(anchor circle)
			)
			(primitives
				(gr_poly
					(pts
						(arc
							(start 0.3048 -0.2032)
							(mid 0.275042 -0.275042)
							(end 0.2032 -0.3048)
						)
						(arc
							(start -0.2032 -0.3048)
							(mid -0.275042 -0.275042)
							(end -0.3048 -0.2032)
						)
						(arc
							(start -0.3048 0.2032)
							(mid -0.275042 0.275042)
							(end -0.2032 0.3048)
						)
						(arc
							(start 0.2032 0.3048)
							(mid 0.275042 0.275042)
							(end 0.3048 0.2032)
						)
					)
					(width 0)
					(fill yes)
				)
			)
		)
	)
	(footprint ""
		(layer "F.Cu")
		(at 248.7676 -13.3604 180)
		(property "Reference" "C463"
			(at 0 0 180)
			(layer "F.SilkS")
			(hide yes)
			(effects
				(font
					(size 1.27 1.27)
				)
			)
		)
		(property "Value" "SC4D7U16V5KX-1-GP"
			(at -0.0762 -6.1214 180)
			(unlocked yes)
			(layer "F.Fab")
			(hide yes)
			(effects
				(font
					(size 1.016 1.016)
					(thickness 0.1524)
				)
			)
		)
		(property "Device Type" "C805H56"
			(at -0.0762 -8.1534 180)
			(unlocked yes)
			(layer "F.Fab")
			(hide yes)
			(effects
				(font
					(size 1.016 1.016)
					(thickness 0.1524)
				)
			)
		)
		(duplicate_pad_numbers_are_jumpers no)
		(fp_line
			(start 0.635 0)
			(end -0.635 0)
			(stroke
				(width 0.508)
				(type default)
			)
			(layer "F.SilkS")
		)
		(fp_rect
			(start -0.9652 1.778)
			(end 0.9652 -1.778)
			(stroke
				(width 0)
				(type default)
			)
			(fill no)
			(layer "F.CrtYd")
		)
		(fp_poly
			(pts
				(xy -0.9652 -1.778) (xy 0.9652 -1.778) (xy 0.9652 1.778) (xy -0.9652 1.778)
			)
			(stroke
				(width 0)
				(type default)
			)
			(fill no)
			(layer "F.Fab")
		)
		(pad "1" smd rect
			(at 0 -0.9652 180)
			(size 1.397 1.143)
			(layers "F.Cu" "F.Mask" "F.Paste")
			(net "DUT_VDDO")
		)
		(pad "2" smd rect
			(at 0 0.9652 180)
			(size 1.397 1.143)
			(layers "F.Cu" "F.Mask" "F.Paste")
			(net "GND")
		)
	)
	(footprint ""
		(layer "F.Cu")
		(at 186.7154 -71.628 180)
		(property "Reference" "C549"
			(at 0 0 180)
			(layer "F.SilkS")
			(hide yes)
			(effects
				(font
					(size 1.27 1.27)
				)
			)
		)
		(property "Value" "SC4D7U16V5KX-1-GP"
			(at -0.0762 -6.1214 180)
			(unlocked yes)
			(layer "F.Fab")
			(hide yes)
			(effects
				(font
					(size 1.016 1.016)
					(thickness 0.1524)
				)
			)
		)
		(property "Device Type" "C805H56"
			(at -0.0762 -8.1534 180)
			(unlocked yes)
			(layer "F.Fab")
			(hide yes)
			(effects
				(font
					(size 1.016 1.016)
					(thickness 0.1524)
				)
			)
		)
		(duplicate_pad_numbers_are_jumpers no)
		(fp_line
			(start 0.635 0)
			(end -0.635 0)
			(stroke
				(width 0.508)
				(type default)
			)
			(layer "F.SilkS")
		)
		(fp_rect
			(start -0.9652 1.778)
			(end 0.9652 -1.778)
			(stroke
				(width 0)
				(type default)
			)
			(fill no)
			(layer "F.CrtYd")
		)
		(fp_poly
			(pts
				(xy -0.9652 -1.778) (xy 0.9652 -1.778) (xy 0.9652 1.778) (xy -0.9652 1.778)
			)
			(stroke
				(width 0)
				(type default)
			)
			(fill no)
			(layer "F.Fab")
		)
		(pad "1" smd rect
			(at 0 -0.9652 180)
			(size 1.397 1.143)
			(layers "F.Cu" "F.Mask" "F.Paste")
			(net "DUT_AVD_PCIE")
		)
		(pad "2" smd rect
			(at 0 0.9652 180)
			(size 1.397 1.143)
			(layers "F.Cu" "F.Mask" "F.Paste")
			(net "GND")
		)
	)
	(footprint ""
		(layer "F.Cu")
		(at 341.99195 -212.420454 180)
		(property "Reference" "C54"
			(at 0 0 180)
			(layer "F.SilkS")
			(hide yes)
			(effects
				(font
					(size 1.27 1.27)
				)
			)
		)
		(property "Value" "SCD22U10V2KX-1GP"
			(at 1.1811 -2.7051 180)
			(unlocked yes)
			(layer "F.Fab")
			(hide yes)
			(effects
				(font
					(size 1.016 1.016)
					(thickness 0.1524)
				)
			)
		)
		(property "Device Type" "C402H22"
			(at 1.1811 -4.2291 180)
			(unlocked yes)
			(layer "F.Fab")
			(hide yes)
			(effects
				(font
					(size 1.016 1.016)
					(thickness 0.1524)
				)
			)
		)
		(duplicate_pad_numbers_are_jumpers no)
		(fp_rect
			(start -0.4318 0.9525)
			(end 0.4318 -0.9525)
			(stroke
				(width 0)
				(type default)
			)
			(fill no)
			(layer "F.CrtYd")
		)
		(fp_rect
			(start -0.4318 0.9525)
			(end 0.4318 -0.9525)
			(stroke
				(width 0)
				(type default)
			)
			(fill no)
			(layer "F.Fab")
		)
		(pad "1" smd custom
			(at 0 -0.4445 180)
			(size 0.1524 0.1524)
			(layers "F.Cu" "F.Mask" "F.Paste")
			(net "PCIE_TX_CAP_P16")
			(options
				(clearance outline)
				(anchor circle)
			)
			(primitives
				(gr_poly
					(pts
						(arc
							(start 0.3048 -0.2032)
							(mid 0.275042 -0.275042)
							(end 0.2032 -0.3048)
						)
						(arc
							(start -0.2032 -0.3048)
							(mid -0.275042 -0.275042)
							(end -0.3048 -0.2032)
						)
						(arc
							(start -0.3048 0.2032)
							(mid -0.275042 0.275042)
							(end -0.2032 0.3048)
						)
						(arc
							(start 0.2032 0.3048)
							(mid 0.275042 0.275042)
							(end 0.3048 0.2032)
						)
					)
					(width 0)
					(fill yes)
				)
			)
		)
		(pad "2" smd custom
			(at 0 0.4445 180)
			(size 0.1524 0.1524)
			(layers "F.Cu" "F.Mask" "F.Paste")
			(net "PCIE_TX_P16")
			(options
				(clearance outline)
				(anchor circle)
			)
			(primitives
				(gr_poly
					(pts
						(arc
							(start 0.3048 -0.2032)
							(mid 0.275042 -0.275042)
							(end 0.2032 -0.3048)
						)
						(arc
							(start -0.2032 -0.3048)
							(mid -0.275042 -0.275042)
							(end -0.3048 -0.2032)
						)
						(arc
							(start -0.3048 0.2032)
							(mid -0.275042 0.275042)
							(end -0.2032 0.3048)
						)
						(arc
							(start 0.2032 0.3048)
							(mid 0.275042 0.275042)
							(end 0.3048 0.2032)
						)
					)
					(width 0)
					(fill yes)
				)
			)
		)
	)
	(footprint ""
		(layer "F.Cu")
		(at 14.097 -125.095)
		(property "Reference" "U12"
			(at 0 0 0)
			(layer "F.SilkS")
			(hide yes)
			(effects
				(font
					(size 1.27 1.27)
				)
			)
		)
		(property "Value" "2N7002DW-7F-GP"
			(at -2.3622 -8.2042 0)
			(unlocked yes)
			(layer "F.Fab")
			(hide yes)
			(effects
				(font
					(size 1.016 1.016)
					(thickness 0.1524)
				)
			)
		)
		(property "Device Type" "SOT-363H44"
			(at -2.3622 -10.1092 0)
			(unlocked yes)
			(layer "F.Fab")
			(hide yes)
			(effects
				(font
					(size 1.016 1.016)
					(thickness 0.1524)
				)
			)
		)
		(duplicate_pad_numbers_are_jumpers no)
		(fp_line
			(start -1.4478 -1.7018)
			(end -1.4478 1.7018)
			(stroke
				(width 0.1524)
				(type default)
			)
			(layer "F.SilkS")
		)
		(fp_line
			(start -1.4478 1.7018)
			(end 1.4478 1.7018)
			(stroke
				(width 0.1524)
				(type default)
			)
			(layer "F.SilkS")
		)
		(fp_line
			(start -1.27 1.524)
			(end -1.27 0.6604)
			(stroke
				(width 0.4826)
				(type default)
			)
			(layer "F.SilkS")
		)
		(fp_line
			(start 1.4478 -1.7018)
			(end -1.4478 -1.7018)
			(stroke
				(width 0.1524)
				(type default)
			)
			(layer "F.SilkS")
		)
		(fp_line
			(start 1.4478 1.7018)
			(end 1.4478 -1.7018)
			(stroke
				(width 0.1524)
				(type default)
			)
			(layer "F.SilkS")
		)
		(fp_poly
			(pts
				(xy -1.524 -1.778) (xy 1.524 -1.778) (xy 1.524 1.778) (xy -1.524 1.778)
			)
			(stroke
				(width 0)
				(type default)
			)
			(fill no)
			(layer "F.CrtYd")
		)
		(fp_poly
			(pts
				(xy -1.524 -1.778) (xy 1.524 -1.778) (xy 1.524 1.778) (xy -1.524 1.778)
			)
			(stroke
				(width 0)
				(type default)
			)
			(fill no)
			(layer "F.Fab")
		)
		(pad "1" smd rect
			(at -0.65024 0.9398)
			(size 0.4064 1.016)
			(layers "F.Cu" "F.Mask" "F.Paste")
			(net "BMC_I2C2_MINI2_SCL_S")
		)
		(pad "2" smd rect
			(at 0 0.9398)
			(size 0.4064 1.016)
			(layers "F.Cu" "F.Mask" "F.Paste")
			(net "I2C2_LS_G2")
		)
		(pad "3" smd rect
			(at 0.65024 0.9398)
			(size 0.4064 1.016)
			(layers "F.Cu" "F.Mask" "F.Paste")
			(net "BMC_I2C2_MINI2_SDA")
		)
		(pad "4" smd rect
			(at 0.65024 -0.9398)
			(size 0.4064 1.016)
			(layers "F.Cu" "F.Mask" "F.Paste")
			(net "BMC_I2C2_MINI2_SDA_S")
		)
		(pad "5" smd rect
			(at 0 -0.9398)
			(size 0.4064 1.016)
			(layers "F.Cu" "F.Mask" "F.Paste")
			(net "I2C2_LS_G1")
		)
		(pad "6" smd rect
			(at -0.65024 -0.9398)
			(size 0.4064 1.016)
			(layers "F.Cu" "F.Mask" "F.Paste")
			(net "BMC_I2C2_MINI2_SCL")
		)
	)
	(footprint ""
		(layer "F.Cu")
		(at 9.779 -71.7804)
		(property "Reference" "C235"
			(at 0 0 0)
			(layer "F.SilkS")
			(hide yes)
			(effects
				(font
					(size 1.27 1.27)
				)
			)
		)
		(property "Value" "SC12P50V2JN-3GP"
			(at 1.1811 -2.7051 0)
			(unlocked yes)
			(layer "F.Fab")
			(hide yes)
			(effects
				(font
					(size 1.016 1.016)
					(thickness 0.1524)
				)
			)
		)
		(property "Device Type" "C402H24"
			(at 1.1811 -4.2291 0)
			(unlocked yes)
			(layer "F.Fab")
			(hide yes)
			(effects
				(font
					(size 1.016 1.016)
					(thickness 0.1524)
				)
			)
		)
		(duplicate_pad_numbers_are_jumpers no)
		(fp_rect
			(start -0.4318 0.9525)
			(end 0.4318 -0.9525)
			(stroke
				(width 0)
				(type default)
			)
			(fill no)
			(layer "F.CrtYd")
		)
		(fp_rect
			(start -0.4318 0.9525)
			(end 0.4318 -0.9525)
			(stroke
				(width 0)
				(type default)
			)
			(fill no)
			(layer "F.Fab")
		)
		(pad "1" smd custom
			(at 0 -0.4445)
			(size 0.1524 0.1524)
			(layers "F.Cu" "F.Mask" "F.Paste")
			(net "GND")
			(options
				(clearance outline)
				(anchor circle)
			)
			(primitives
				(gr_poly
					(pts
						(arc
							(start 0.3048 -0.2032)
							(mid 0.275042 -0.275042)
							(end 0.2032 -0.3048)
						)
						(arc
							(start -0.2032 -0.3048)
							(mid -0.275042 -0.275042)
							(end -0.3048 -0.2032)
						)
						(arc
							(start -0.3048 0.2032)
							(mid -0.275042 0.275042)
							(end -0.2032 0.3048)
						)
						(arc
							(start 0.2032 0.3048)
							(mid 0.275042 0.275042)
							(end 0.3048 0.2032)
						)
					)
					(width 0)
					(fill yes)
				)
			)
		)
		(pad "2" smd custom
			(at 0 0.4445)
			(size 0.1524 0.1524)
			(layers "F.Cu" "F.Mask" "F.Paste")
			(net "XTAL_OUT_I210_R")
			(options
				(clearance outline)
				(anchor circle)
			)
			(primitives
				(gr_poly
					(pts
						(arc
							(start 0.3048 -0.2032)
							(mid 0.275042 -0.275042)
							(end 0.2032 -0.3048)
						)
						(arc
							(start -0.2032 -0.3048)
							(mid -0.275042 -0.275042)
							(end -0.3048 -0.2032)
						)
						(arc
							(start -0.3048 0.2032)
							(mid -0.275042 0.275042)
							(end -0.2032 0.3048)
						)
						(arc
							(start 0.2032 0.3048)
							(mid 0.275042 0.275042)
							(end 0.3048 0.2032)
						)
					)
					(width 0)
					(fill yes)
				)
			)
		)
	)
	(footprint ""
		(layer "F.Cu")
		(at 15.696946 -95.086678 180)
		(property "Reference" "C155"
			(at 0 0 180)
			(layer "F.SilkS")
			(hide yes)
			(effects
				(font
					(size 1.27 1.27)
				)
			)
		)
		(property "Value" "SCD1U16V2JX-1-GP"
			(at 1.1811 -2.7051 180)
			(unlocked yes)
			(layer "F.Fab")
			(hide yes)
			(effects
				(font
					(size 1.016 1.016)
					(thickness 0.1524)
				)
			)
		)
		(property "Device Type" "C402H22"
			(at 1.1811 -4.2291 180)
			(unlocked yes)
			(layer "F.Fab")
			(hide yes)
			(effects
				(font
					(size 1.016 1.016)
					(thickness 0.1524)
				)
			)
		)
		(duplicate_pad_numbers_are_jumpers no)
		(fp_rect
			(start -0.4318 0.9525)
			(end 0.4318 -0.9525)
			(stroke
				(width 0)
				(type default)
			)
			(fill no)
			(layer "F.CrtYd")
		)
		(fp_rect
			(start -0.4318 0.9525)
			(end 0.4318 -0.9525)
			(stroke
				(width 0)
				(type default)
			)
			(fill no)
			(layer "F.Fab")
		)
		(pad "1" smd custom
			(at 0 -0.4445 180)
			(size 0.1524 0.1524)
			(layers "F.Cu" "F.Mask" "F.Paste")
			(net "Q20_G")
			(options
				(clearance outline)
				(anchor circle)
			)
			(primitives
				(gr_poly
					(pts
						(arc
							(start 0.3048 -0.2032)
							(mid 0.275042 -0.275042)
							(end 0.2032 -0.3048)
						)
						(arc
							(start -0.2032 -0.3048)
							(mid -0.275042 -0.275042)
							(end -0.3048 -0.2032)
						)
						(arc
							(start -0.3048 0.2032)
							(mid -0.275042 0.275042)
							(end -0.2032 0.3048)
						)
						(arc
							(start 0.2032 0.3048)
							(mid 0.275042 0.275042)
							(end 0.3048 0.2032)
						)
					)
					(width 0)
					(fill yes)
				)
			)
		)
		(pad "2" smd custom
			(at 0 0.4445 180)
			(size 0.1524 0.1524)
			(layers "F.Cu" "F.Mask" "F.Paste")
			(net "GND")
			(options
				(clearance outline)
				(anchor circle)
			)
			(primitives
				(gr_poly
					(pts
						(arc
							(start 0.3048 -0.2032)
							(mid 0.275042 -0.275042)
							(end 0.2032 -0.3048)
						)
						(arc
							(start -0.2032 -0.3048)
							(mid -0.275042 -0.275042)
							(end -0.3048 -0.2032)
						)
						(arc
							(start -0.3048 0.2032)
							(mid -0.275042 0.275042)
							(end -0.2032 0.3048)
						)
						(arc
							(start 0.2032 0.3048)
							(mid 0.275042 0.275042)
							(end 0.3048 0.2032)
						)
					)
					(width 0)
					(fill yes)
				)
			)
		)
	)
)
